#ISCELL
  mstr_misc dns *
  *
#ISCELL
  pure_quanta quanta_title_block_c *
  *
#ISCELL
  pure_quanta_power cad_note *
  *
#CELL
  pure_quanta q_res *
  page138_i100
#ISCELL
  standard offpage *
  page138_i101
#ISCELL
  standard offpage *
  page138_i102
#ISCELL
  standard offpage *
  page138_i103
#ISCELL
  standard offpage *
  page138_i104
#CELL
  pure_quanta q_res *
  page138_i109
#CELL
  pure_quanta q_res *
  page138_i110
#CELL
  pure_quanta iml3112y2b000ncg8 *
  page138_i111
#CELL
  pure_quanta q_cap *
  page138_i112
#CELL
  pure_quanta q_cap *
  page138_i113
#CELL
  pure_quanta pi3csw12zuaex *
  page138_i114
#ISCELL
  pure_quanta_power p1v0 *
  page138_i13
#CELL
  pure_quanta q_res *
  page138_i14
#CELL
  pure_quanta q_res *
  page138_i15
#CELL
  pure_quanta q_res *
  page138_i16
#CELL
  pure_quanta q_res *
  page138_i17
#ISCELL
  pure_quanta_power universal_gnd *
  page138_i18
#ISCELL
  standard offpage *
  page138_i2
#ISCELL
  pure_quanta_power universal_gnd *
  page138_i21
#CELL
  pure_quanta q_res *
  page138_i22
#CELL
  pure_quanta q_res *
  page138_i23
#ISCELL
  pure_quanta_power universal_gnd *
  page138_i26
#CELL
  pure_quanta q_res *
  page138_i27
#ISCELL
  pure_quanta_power universal_gnd *
  page138_i28
#CELL
  pure_quanta q_res *
  page138_i30
#ISCELL
  pure_quanta_power universal_gnd *
  page138_i31
#ISCELL
  pure_quanta_power p1v0 *
  page138_i33
#CELL
  pure_quanta q_res *
  page138_i34
#CELL
  pure_quanta q_res *
  page138_i35
#CELL
  pure_quanta q_res *
  page138_i38
#CELL
  pure_quanta q_res *
  page138_i39
#ISCELL
  standard offpage *
  page138_i40
#ISCELL
  standard offpage *
  page138_i42
#ISCELL
  standard offpage *
  page138_i44
#ISCELL
  standard offpage *
  page138_i45
#ISCELL
  standard offpage *
  page138_i46
#ISCELL
  standard offpage *
  page138_i47
#ISCELL
  standard offpage *
  page138_i48
#ISCELL
  standard offpage *
  page138_i49
#CELL
  pure_quanta q_res *
  page138_i5
#ISCELL
  standard offpage *
  page138_i50
#ISCELL
  standard offpage *
  page138_i51
#CELL
  pure_quanta q_res *
  page138_i52
#CELL
  pure_quanta q_res *
  page138_i53
#CELL
  pure_quanta q_res *
  page138_i54
#CELL
  pure_quanta q_res *
  page138_i55
#CELL
  pure_quanta q_res *
  page138_i56
#CELL
  pure_quanta q_res *
  page138_i57
#CELL
  pure_quanta q_res *
  page138_i58
#ISCELL
  pure_quanta_power vcc_core *
  page138_i59
#CELL
  pure_quanta q_res *
  page138_i6
#CELL
  pure_quanta q_res *
  page138_i60
#ISCELL
  standard offpage *
  page138_i61
#ISCELL
  standard offpage *
  page138_i62
#ISCELL
  standard offpage *
  page138_i63
#ISCELL
  standard offpage *
  page138_i64
#ISCELL
  pure_quanta_power vcc_core *
  page138_i65
#CELL
  pure_quanta pi3csw12zuaex *
  page138_i67
#CELL
  pure_quanta q_cap *
  page138_i69
#ISCELL
  pure_quanta_power universal_gnd *
  page138_i70
#ISCELL
  standard offpage *
  page138_i71
#ISCELL
  standard offpage *
  page138_i72
#CELL
  pure_quanta q_res *
  page138_i73
#CELL
  pure_quanta q_res *
  page138_i74
#CELL
  pure_quanta q_res *
  page138_i75
#CELL
  pure_quanta q_res *
  page138_i76
#ISCELL
  standard offpage *
  page138_i77
#ISCELL
  standard offpage *
  page138_i78
#ISCELL
  standard offpage *
  page138_i79
#ISCELL
  pure_quanta_power p1v0 *
  page138_i81
#ISCELL
  pure_quanta_power p1v0 *
  page138_i82
#ISCELL
  standard offpage *
  page138_i84
#ISCELL
  standard offpage *
  page138_i85
#ISCELL
  pure_quanta_power universal_gnd *
  page138_i86
#ISCELL
  pure_quanta_power p1v0 *
  page138_i87
#ISCELL
  pure_quanta_power universal_gnd *
  page138_i88
#CELL
  pure_quanta q_cap *
  page138_i89
#CELL
  pure_quanta q_res *
  page138_i91
#CELL
  pure_quanta q_res *
  page138_i92
#CELL
  pure_quanta q_res *
  page138_i93
#CELL
  pure_quanta q_res *
  page138_i94
#ISCELL
  standard offpage *
  page138_i95
#ISCELL
  standard offpage *
  page138_i96
#ISCELL
  standard offpage *
  page138_i97
#ISCELL
  standard offpage *
  page138_i98
#CELL
  pure_quanta q_res *
  page138_i99
